# BASEBOARD_FAB2 (Tioga Pass) — schematic netlist excerpt (pin names and nets, part order shuffled) for the footprints in the layout excerpt that follows; sources: Cadence DE-HDL packaged netlist, KiCad conversion of Wiwynn_Tioga_Pass_MB.brd

R7P18  RES  150.0 1% CHIP  pkg 0402  page 92 : A = PVCCIO_CPU0 ; B = H_CPU1_CATERR_G_N
R7R1  RES  51.1 1.0% CHIP  pkg 0402  page 214 : A = PVCCIO_CPU1 ; B = GND
R9R11  RES  0.0 5% CHIP  pkg 0402  page 207 : A = VR_PVCCIN_CPU1_PH2_VCIN ; B = P5V_STBY

(kicad_pcb
	(version 20260206)
	(generator "pcbnew")
	(generator_version "10.0")
	(general
		(thickness 1.6)
		(legacy_teardrops no)
	)
	(paper "A4")
	(title_block
		(title "Wiwynn_Tioga_Pass_MB.brd")
		(comment 1 "Tioga Pass / footprints 4058-4060 of 4770")
	)
	(layers
		(0 "F.Cu" signal "TOP")
		(4 "In1.Cu" signal "L2GND")
		(6 "In2.Cu" signal "L3")
		(8 "In3.Cu" signal "L4GND")
		(10 "In4.Cu" signal "L5")
		(12 "In5.Cu" signal "L6GND")
		(14 "In6.Cu" signal "L7VCC")
		(16 "In7.Cu" signal "L8VCC")
		(18 "In8.Cu" signal "L9GND")
		(20 "In9.Cu" signal "L10")
		(22 "In10.Cu" signal "L11GND")
		(24 "In11.Cu" signal "L12")
		(26 "In12.Cu" signal "L13GND")
		(2 "B.Cu" signal "BOTTOM")
		(9 "F.Adhes" user "F.Adhesive")
		(11 "B.Adhes" user "B.Adhesive")
		(13 "F.Paste" user "Package Geometry/Pastemask Top")
		(15 "B.Paste" user "Package Geometry/Pastemask Bottom")
		(5 "F.SilkS" user "Ref Des/Silkscreen Top")
		(7 "B.SilkS" user "Ref Des/Silkscreen Bottom")
		(1 "F.Mask" user "Board Geometry/Soldermask Top")
		(3 "B.Mask" user "Board Geometry/Soldermask Bottom")
		(17 "Dwgs.User" user "User.Drawings")
		(19 "Cmts.User" user "User.Comments")
		(21 "Eco1.User" user "User.Eco1")
		(23 "Eco2.User" user "User.Eco2")
		(25 "Edge.Cuts" user "Board Geometry/Outline")
		(27 "Margin" user)
		(31 "F.CrtYd" user "Package Geometry/Place Bound Top")
		(29 "B.CrtYd" user "Package Geometry/Place Bound Bottom")
		(35 "F.Fab" user "Ref Des/Assembly Top")
		(33 "B.Fab" user "Ref Des/Assembly Bottom")
	)
	(footprint ""
		(layer "B.Cu")
		(at 162.179 -70.358 180)
		(property "Reference" "R7P18"
			(at 0 0 0)
			(layer "B.SilkS")
			(hide yes)
			(effects
				(font
					(size 1.27 1.27)
				)
				(justify mirror)
			)
		)
		(property "Value" ""
			(at 0 0 0)
			(layer "B.Fab")
			(effects
				(font
					(size 1.27 1.27)
				)
				(justify mirror)
			)
		)
		(duplicate_pad_numbers_are_jumpers no)
		(fp_poly
			(pts
				(xy 0.2794 -0.1016) (xy -0.2794 -0.1016) (xy -0.2794 0.9906) (xy 0.2794 0.9906)
			)
			(stroke
				(width 0)
				(type default)
			)
			(fill no)
			(layer "B.CrtYd")
		)
		(fp_line
			(start 0.2794 0.9906)
			(end -0.2794 0.9906)
			(stroke
				(width 0.1)
				(type default)
			)
			(layer "B.Fab")
		)
		(fp_line
			(start 0.2794 -0.1016)
			(end 0.2794 0.9906)
			(stroke
				(width 0.1)
				(type default)
			)
			(layer "B.Fab")
		)
		(fp_line
			(start -0.2794 0.9906)
			(end -0.2794 -0.1016)
			(stroke
				(width 0.1)
				(type default)
			)
			(layer "B.Fab")
		)
		(fp_line
			(start -0.2794 -0.1016)
			(end 0.2794 -0.1016)
			(stroke
				(width 0.1)
				(type default)
			)
			(layer "B.Fab")
		)
		(pad "1" smd rect
			(at 0 0)
			(size 0.508 0.508)
			(layers "B.Cu" "B.Mask" "B.Paste")
			(net "PVCCIO_CPU0")
		)
		(pad "2" smd rect
			(at 0 0.889)
			(size 0.508 0.508)
			(layers "B.Cu" "B.Mask" "B.Paste")
			(net "H_CPU1_CATERR_G_N")
		)
		(zone
			(layer "B.Cu")
			(hatch none 0.5)
			(connect_pads
				(clearance 0)
			)
			(min_thickness 0.25)
			(keepout
				(tracks not_allowed)
				(vias allowed)
				(pads allowed)
				(copperpour not_allowed)
				(footprints allowed)
			)
			(placement
				(enabled no)
				(sheetname "")
			)
			(fill
				(thermal_gap 0.5)
				(thermal_bridge_width 0.5)
				(island_removal_mode 0)
			)
			(polygon
				(pts
					(xy 161.925 -70.993) (xy 162.433 -70.993) (xy 162.433 -70.612) (xy 161.925 -70.612)
				)
			)
		)
		(zone
			(layer "B.Cu")
			(hatch none 0.5)
			(connect_pads
				(clearance 0)
			)
			(min_thickness 0.25)
			(keepout
				(tracks allowed)
				(vias not_allowed)
				(pads allowed)
				(copperpour not_allowed)
				(footprints allowed)
			)
			(placement
				(enabled no)
				(sheetname "")
			)
			(fill
				(thermal_gap 0.5)
				(thermal_bridge_width 0.5)
				(island_removal_mode 0)
			)
			(polygon
				(pts
					(xy 161.925 -70.612) (xy 162.433 -70.612) (xy 162.433 -70.993) (xy 161.925 -70.993)
				)
			)
		)
	)
	(footprint ""
		(layer "B.Cu")
		(at 162.175952 -62.487302 180)
		(property "Reference" "R7R1"
			(at 0 0 0)
			(layer "B.SilkS")
			(hide yes)
			(effects
				(font
					(size 1.27 1.27)
				)
				(justify mirror)
			)
		)
		(property "Value" ""
			(at 0 0 0)
			(layer "B.Fab")
			(effects
				(font
					(size 1.27 1.27)
				)
				(justify mirror)
			)
		)
		(duplicate_pad_numbers_are_jumpers no)
		(fp_poly
			(pts
				(xy 0.2794 -0.1016) (xy -0.2794 -0.1016) (xy -0.2794 0.9906) (xy 0.2794 0.9906)
			)
			(stroke
				(width 0)
				(type default)
			)
			(fill no)
			(layer "B.CrtYd")
		)
		(fp_line
			(start 0.2794 0.9906)
			(end -0.2794 0.9906)
			(stroke
				(width 0.1)
				(type default)
			)
			(layer "B.Fab")
		)
		(fp_line
			(start 0.2794 -0.1016)
			(end 0.2794 0.9906)
			(stroke
				(width 0.1)
				(type default)
			)
			(layer "B.Fab")
		)
		(fp_line
			(start -0.2794 0.9906)
			(end -0.2794 -0.1016)
			(stroke
				(width 0.1)
				(type default)
			)
			(layer "B.Fab")
		)
		(fp_line
			(start -0.2794 -0.1016)
			(end 0.2794 -0.1016)
			(stroke
				(width 0.1)
				(type default)
			)
			(layer "B.Fab")
		)
		(pad "1" smd rect
			(at 0 0)
			(size 0.508 0.508)
			(layers "B.Cu" "B.Mask" "B.Paste")
			(net "PVCCIO_CPU1")
		)
		(pad "2" smd rect
			(at 0 0.889)
			(size 0.508 0.508)
			(layers "B.Cu" "B.Mask" "B.Paste")
			(net "GND")
		)
		(zone
			(layer "B.Cu")
			(hatch none 0.5)
			(connect_pads
				(clearance 0)
			)
			(min_thickness 0.25)
			(keepout
				(tracks not_allowed)
				(vias allowed)
				(pads allowed)
				(copperpour not_allowed)
				(footprints allowed)
			)
			(placement
				(enabled no)
				(sheetname "")
			)
			(fill
				(thermal_gap 0.5)
				(thermal_bridge_width 0.5)
				(island_removal_mode 0)
			)
			(polygon
				(pts
					(xy 161.921952 -63.122302) (xy 162.429952 -63.122302) (xy 162.429952 -62.741302) (xy 161.921952 -62.741302)
				)
			)
		)
		(zone
			(layer "B.Cu")
			(hatch none 0.5)
			(connect_pads
				(clearance 0)
			)
			(min_thickness 0.25)
			(keepout
				(tracks allowed)
				(vias not_allowed)
				(pads allowed)
				(copperpour not_allowed)
				(footprints allowed)
			)
			(placement
				(enabled no)
				(sheetname "")
			)
			(fill
				(thermal_gap 0.5)
				(thermal_bridge_width 0.5)
				(island_removal_mode 0)
			)
			(polygon
				(pts
					(xy 161.921952 -62.741302) (xy 162.429952 -62.741302) (xy 162.429952 -63.122302) (xy 161.921952 -63.122302)
				)
			)
		)
	)
	(footprint ""
		(layer "B.Cu")
		(at 32.258 -62.6364 90)
		(property "Reference" "R9R11"
			(at 0 0 90)
			(layer "B.SilkS")
			(hide yes)
			(effects
				(font
					(size 1.27 1.27)
				)
				(justify mirror)
			)
		)
		(property "Value" ""
			(at 0 0 90)
			(layer "B.Fab")
			(effects
				(font
					(size 1.27 1.27)
				)
				(justify mirror)
			)
		)
		(duplicate_pad_numbers_are_jumpers no)
		(fp_poly
			(pts
				(xy 0.2794 -0.1016) (xy -0.2794 -0.1016) (xy -0.2794 0.9906) (xy 0.2794 0.9906)
			)
			(stroke
				(width 0)
				(type default)
			)
			(fill no)
			(layer "B.CrtYd")
		)
		(fp_line
			(start 0.2794 -0.1016)
			(end 0.2794 0.9906)
			(stroke
				(width 0.1)
				(type default)
			)
			(layer "B.Fab")
		)
		(fp_line
			(start -0.2794 -0.1016)
			(end 0.2794 -0.1016)
			(stroke
				(width 0.1)
				(type default)
			)
			(layer "B.Fab")
		)
		(fp_line
			(start 0.2794 0.9906)
			(end -0.2794 0.9906)
			(stroke
				(width 0.1)
				(type default)
			)
			(layer "B.Fab")
		)
		(fp_line
			(start -0.2794 0.9906)
			(end -0.2794 -0.1016)
			(stroke
				(width 0.1)
				(type default)
			)
			(layer "B.Fab")
		)
		(pad "1" smd rect
			(at 0 0 270)
			(size 0.508 0.508)
			(layers "B.Cu" "B.Mask" "B.Paste")
			(net "VR_PVCCIN_CPU1_PH2_VCIN")
		)
		(pad "2" smd rect
			(at 0 0.889 270)
			(size 0.508 0.508)
			(layers "B.Cu" "B.Mask" "B.Paste")
			(net "P5V_STBY")
		)
		(zone
			(layer "B.Cu")
			(hatch none 0.5)
			(connect_pads
				(clearance 0)
			)
			(min_thickness 0.25)
			(keepout
				(tracks allowed)
				(vias not_allowed)
				(pads allowed)
				(copperpour not_allowed)
				(footprints allowed)
			)
			(placement
				(enabled no)
				(sheetname "")
			)
			(fill
				(thermal_gap 0.5)
				(thermal_bridge_width 0.5)
				(island_removal_mode 0)
			)
			(polygon
				(pts
					(xy 32.512 -62.8904) (xy 32.512 -62.3824) (xy 32.893 -62.3824) (xy 32.893 -62.8904)
				)
			)
		)
		(zone
			(layer "B.Cu")
			(hatch none 0.5)
			(connect_pads
				(clearance 0)
			)
			(min_thickness 0.25)
			(keepout
				(tracks not_allowed)
				(vias allowed)
				(pads allowed)
				(copperpour not_allowed)
				(footprints allowed)
			)
			(placement
				(enabled no)
				(sheetname "")
			)
			(fill
				(thermal_gap 0.5)
				(thermal_bridge_width 0.5)
				(island_removal_mode 0)
			)
			(polygon
				(pts
					(xy 32.893 -62.8904) (xy 32.893 -62.3824) (xy 32.512 -62.3824) (xy 32.512 -62.8904)
				)
			)
		)
	)
)
